# T6G (Grand Teton) — schematic netlist excerpt (pin names and nets, part order shuffled) for the footprints in the layout excerpt that follows; sources: Cadence DE-HDL packaged netlist, KiCad conversion of 04192023_DAF0TMB3IC0_F0TG_MB_C_brd_V02_OCP.brd

R1102  Q_RES  1K 1% CHIP  pkg 0201LF  page 309 : A = RT_CPU0_P3_ADDR1 ; B = GND

Q11  MOSFET_DUAL_6P  2N7002KDW IC  pkg SOT363XD  page 166
  S1  = GND
  G1  = FM_SMERR_BUF_R_LED_N
  D2  = SMERR_LED_N
  S2  = GND
  G2  = SMERR_LED
  D1  = SMERR_LED

PR6524  Q_RES  20K 1% CHIP  pkg 0402LF  page 361 : A = P1V8_RETIMER_CPU1_FB ; B = P1V8_CPU1_RT_1D

(kicad_pcb
	(version 20260206)
	(generator "pcbnew")
	(generator_version "10.0")
	(general
		(thickness 1.6)
		(legacy_teardrops no)
	)
	(paper "A4")
	(title_block
		(title "04192023_DAF0TMB3IC0_F0TG_MB_C_brd_V02_OCP.brd")
		(comment 1 "Grand Teton / footprints 1594-1596 of 8354")
	)
	(layers
		(0 "F.Cu" signal "TOP")
		(4 "In1.Cu" signal "GND")
		(6 "In2.Cu" signal "IN1")
		(8 "In3.Cu" signal "GND1")
		(10 "In4.Cu" signal "IN2")
		(12 "In5.Cu" signal "GND2")
		(14 "In6.Cu" signal "IN3")
		(16 "In7.Cu" signal "GND3")
		(18 "In8.Cu" signal "VCC")
		(20 "In9.Cu" signal "VCC1")
		(22 "In10.Cu" signal "GND4")
		(24 "In11.Cu" signal "IN4")
		(26 "In12.Cu" signal "GND5")
		(28 "In13.Cu" signal "IN5")
		(30 "In14.Cu" signal "GND6")
		(32 "In15.Cu" signal "IN6")
		(34 "In16.Cu" signal "GND7")
		(2 "B.Cu" signal "BOTTOM")
		(9 "F.Adhes" user "F.Adhesive")
		(11 "B.Adhes" user "B.Adhesive")
		(13 "F.Paste" user "Package Geometry/Pastemask Top")
		(15 "B.Paste" user "Package Geometry/Pastemask Bottom")
		(5 "F.SilkS" user "Ref Des/Silkscreen Top")
		(7 "B.SilkS" user "Ref Des/Silkscreen Bottom")
		(1 "F.Mask" user "Board Geometry/Soldermask Top")
		(3 "B.Mask" user "Board Geometry/Soldermask Bottom")
		(17 "Dwgs.User" user "User.Drawings")
		(19 "Cmts.User" user "User.Comments")
		(21 "Eco1.User" user "User.Eco1")
		(23 "Eco2.User" user "User.Eco2")
		(25 "Edge.Cuts" user "Board Geometry/Outline")
		(27 "Margin" user)
		(31 "F.CrtYd" user "Package Geometry/Place Bound Top")
		(29 "B.CrtYd" user "Package Geometry/Place Bound Bottom")
		(35 "F.Fab" user "Ref Des/Assembly Top")
		(33 "B.Fab" user "Ref Des/Assembly Bottom")
	)
	(footprint ""
		(layer "F.Cu")
		(at 343.994486 -20.08505 -90)
		(property "Reference" "Q11"
			(at -1.866138 -2.810002 90)
			(unlocked yes)
			(layer "F.SilkS")
			(effects
				(font
					(size 0.7874 0.5842)
					(thickness 0.1524)
				)
				(justify left)
			)
		)
		(property "Value" ""
			(at 0 0 270)
			(layer "F.Fab")
			(effects
				(font
					(size 1.27 1.27)
				)
			)
		)
		(duplicate_pad_numbers_are_jumpers no)
		(fp_line
			(start -1.332738 1.100074)
			(end -1.332738 -1.100074)
			(stroke
				(width 0.1524)
				(type default)
			)
			(layer "F.SilkS")
		)
		(fp_line
			(start 1.332738 1.100074)
			(end -1.332738 1.100074)
			(stroke
				(width 0.1524)
				(type default)
			)
			(layer "F.SilkS")
		)
		(fp_line
			(start 0 -0.541274)
			(end 0.4826 -1.100074)
			(stroke
				(width 0.1524)
				(type default)
			)
			(layer "F.SilkS")
		)
		(fp_line
			(start -1.332738 -1.100074)
			(end -0.4826 -1.100074)
			(stroke
				(width 0.1524)
				(type default)
			)
			(layer "F.SilkS")
		)
		(fp_line
			(start -0.4826 -1.100074)
			(end 0 -0.541274)
			(stroke
				(width 0.1524)
				(type default)
			)
			(layer "F.SilkS")
		)
		(fp_line
			(start 0.4826 -1.100074)
			(end 1.332738 -1.100074)
			(stroke
				(width 0.1524)
				(type default)
			)
			(layer "F.SilkS")
		)
		(fp_line
			(start 1.332738 -1.100074)
			(end 1.332738 1.100074)
			(stroke
				(width 0.1524)
				(type default)
			)
			(layer "F.SilkS")
		)
		(fp_poly
			(pts
				(xy -2.009902 -0.663702) (xy -2.711958 -0.312674) (xy -2.711958 -1.01473)
			)
			(stroke
				(width 0)
				(type default)
			)
			(fill yes)
			(layer "F.SilkS")
		)
		(fp_line
			(start -0.674878 1.100074)
			(end -0.674878 -1.100074)
			(stroke
				(width 0.1)
				(type default)
			)
			(layer "F.Fab")
		)
		(fp_line
			(start 0.674878 1.100074)
			(end -0.674878 1.100074)
			(stroke
				(width 0.1)
				(type default)
			)
			(layer "F.Fab")
		)
		(fp_line
			(start -0.674878 -1.100074)
			(end 0.674878 -1.100074)
			(stroke
				(width 0.1)
				(type default)
			)
			(layer "F.Fab")
		)
		(fp_line
			(start 0.674878 -1.100074)
			(end 0.674878 1.100074)
			(stroke
				(width 0.1)
				(type default)
			)
			(layer "F.Fab")
		)
		(fp_poly
			(pts
				(xy -2.2352 -0.298958) (xy -2.2352 -1.001014) (xy -1.533144 -0.649986)
			)
			(stroke
				(width 0)
				(type default)
			)
			(fill yes)
			(layer "F.Fab")
		)
		(pad "1" smd rect
			(at -0.94996 -0.649986)
			(size 0.4318 0.508)
			(layers "F.Cu" "F.Mask" "F.Paste")
			(net "GND")
		)
		(pad "2" smd rect
			(at -0.94996 0)
			(size 0.4318 0.508)
			(layers "F.Cu" "F.Mask" "F.Paste")
			(net "FM_SMERR_BUF_R_LED_N")
		)
		(pad "3" smd rect
			(at -0.94996 0.649986)
			(size 0.4318 0.508)
			(layers "F.Cu" "F.Mask" "F.Paste")
			(net "SMERR_LED_N")
		)
		(pad "4" smd rect
			(at 0.94996 0.649986)
			(size 0.4318 0.508)
			(layers "F.Cu" "F.Mask" "F.Paste")
			(net "GND")
		)
		(pad "5" smd rect
			(at 0.94996 0)
			(size 0.4318 0.508)
			(layers "F.Cu" "F.Mask" "F.Paste")
			(net "SMERR_LED")
		)
		(pad "6" smd rect
			(at 0.94996 -0.649986)
			(size 0.4318 0.508)
			(layers "F.Cu" "F.Mask" "F.Paste")
			(net "SMERR_LED")
		)
	)
	(footprint ""
		(layer "F.Cu")
		(at 395.388084 -390.652)
		(property "Reference" "R1102"
			(at 0 0 0)
			(layer "F.SilkS")
			(hide yes)
			(effects
				(font
					(size 1.27 1.27)
				)
			)
		)
		(property "Value" ""
			(at 0 0 0)
			(layer "F.Fab")
			(effects
				(font
					(size 1.27 1.27)
				)
			)
		)
		(duplicate_pad_numbers_are_jumpers no)
		(fp_line
			(start -0.32512 -0.175006)
			(end 0.32512 -0.175006)
			(stroke
				(width 0.1)
				(type default)
			)
			(layer "F.Fab")
		)
		(fp_line
			(start -0.32512 0.175006)
			(end -0.32512 -0.175006)
			(stroke
				(width 0.1)
				(type default)
			)
			(layer "F.Fab")
		)
		(fp_line
			(start 0.32512 -0.175006)
			(end 0.32512 0.175006)
			(stroke
				(width 0.1)
				(type default)
			)
			(layer "F.Fab")
		)
		(fp_line
			(start 0.32512 0.175006)
			(end -0.32512 0.175006)
			(stroke
				(width 0.1)
				(type default)
			)
			(layer "F.Fab")
		)
		(pad "1" smd rect
			(at -0.2667 0)
			(size 0.3048 0.381)
			(layers "F.Cu" "F.Mask" "F.Paste")
			(net "RT_CPU0_P3_ADDR1")
		)
		(pad "2" smd rect
			(at 0.2667 0 180)
			(size 0.3048 0.381)
			(layers "F.Cu" "F.Mask" "F.Paste")
			(net "GND")
		)
	)
	(footprint ""
		(layer "F.Cu")
		(at 226.915472 -290.341812 90)
		(property "Reference" "PR6524"
			(at 0 0 90)
			(layer "F.SilkS")
			(hide yes)
			(effects
				(font
					(size 1.27 1.27)
				)
			)
		)
		(property "Value" ""
			(at 0 0 90)
			(layer "F.Fab")
			(effects
				(font
					(size 1.27 1.27)
				)
			)
		)
		(duplicate_pad_numbers_are_jumpers no)
		(fp_line
			(start 0.7874 -0.4064)
			(end 0.7874 0.4064)
			(stroke
				(width 0.1524)
				(type default)
			)
			(layer "F.SilkS")
		)
		(fp_line
			(start -0.7874 -0.4064)
			(end 0.7874 -0.4064)
			(stroke
				(width 0.1524)
				(type default)
			)
			(layer "F.SilkS")
		)
		(fp_line
			(start 0.7874 0.4064)
			(end -0.7874 0.4064)
			(stroke
				(width 0.1524)
				(type default)
			)
			(layer "F.SilkS")
		)
		(fp_line
			(start -0.7874 0.4064)
			(end -0.7874 -0.4064)
			(stroke
				(width 0.1524)
				(type default)
			)
			(layer "F.SilkS")
		)
		(fp_line
			(start -0.12065 -0.305054)
			(end -0.12065 -0.2794)
			(stroke
				(width 0.1)
				(type default)
			)
			(layer "F.Fab")
		)
		(fp_line
			(start -0.67945 -0.305054)
			(end -0.12065 -0.305054)
			(stroke
				(width 0.1)
				(type default)
			)
			(layer "F.Fab")
		)
		(fp_line
			(start 0.67945 -0.3048)
			(end 0.67945 0.3048)
			(stroke
				(width 0.1)
				(type default)
			)
			(layer "F.Fab")
		)
		(fp_line
			(start 0.12065 -0.3048)
			(end 0.67945 -0.3048)
			(stroke
				(width 0.1)
				(type default)
			)
			(layer "F.Fab")
		)
		(fp_line
			(start 0.12065 -0.2794)
			(end 0.12065 -0.3048)
			(stroke
				(width 0.1)
				(type default)
			)
			(layer "F.Fab")
		)
		(fp_line
			(start -0.12065 -0.2794)
			(end 0.12065 -0.2794)
			(stroke
				(width 0.1)
				(type default)
			)
			(layer "F.Fab")
		)
		(fp_line
			(start 0.120396 0.2794)
			(end -0.12065 0.2794)
			(stroke
				(width 0.1)
				(type default)
			)
			(layer "F.Fab")
		)
		(fp_line
			(start -0.12065 0.2794)
			(end -0.12065 0.3048)
			(stroke
				(width 0.1)
				(type default)
			)
			(layer "F.Fab")
		)
		(fp_line
			(start 0.67945 0.3048)
			(end 0.120396 0.3048)
			(stroke
				(width 0.1)
				(type default)
			)
			(layer "F.Fab")
		)
		(fp_line
			(start 0.120396 0.3048)
			(end 0.120396 0.2794)
			(stroke
				(width 0.1)
				(type default)
			)
			(layer "F.Fab")
		)
		(fp_line
			(start -0.12065 0.3048)
			(end -0.67945 0.3048)
			(stroke
				(width 0.1)
				(type default)
			)
			(layer "F.Fab")
		)
		(fp_line
			(start -0.67945 0.3048)
			(end -0.67945 -0.305054)
			(stroke
				(width 0.1)
				(type default)
			)
			(layer "F.Fab")
		)
		(pad "1" smd circle
			(at -0.40005 0 90)
			(size 0 0)
			(layers "F.Cu" "F.Mask" "F.Paste")
			(net "P1V8_RETIMER_CPU1_FB")
		)
		(pad "2" smd circle
			(at 0.40005 0 90)
			(size 0 0)
			(layers "F.Cu" "F.Mask" "F.Paste")
			(net "P1V8_CPU1_RT_1D")
		)
	)
)
